# BASEBOARD_FAB2 (Tioga Pass) — schematic netlist excerpt (pin names and nets, part order shuffled) for the footprints in the layout excerpt that follows; sources: Cadence DE-HDL packaged netlist, KiCad conversion of Wiwynn_Tioga_Pass_MB.brd

R7F32  RES  10.0K 1% CHIP  pkg 0402  page 153 : A = P3V3_STBY ; B = PU_BIOS_SPI_HOLD0_N
RF2  RES  1.0K 0.1% CHIP  pkg 0402  page 201 : A = VR_PVCCIN_CPU0_AIREF2 ; B = ISENSE_PVCCIN_CPU0_PH2_IMON
R1D20  RES  200.0K 1% CHIP  pkg 0402  page 200 : A = A_HSC_CSOUT ; B = A_HSC_HIGH

(kicad_pcb
	(version 20260206)
	(generator "pcbnew")
	(generator_version "10.0")
	(general
		(thickness 1.6)
		(legacy_teardrops no)
	)
	(paper "A4")
	(title_block
		(title "Wiwynn_Tioga_Pass_MB.brd")
		(comment 1 "Tioga Pass / footprints 927-929 of 4770")
	)
	(layers
		(0 "F.Cu" signal "TOP")
		(4 "In1.Cu" signal "L2GND")
		(6 "In2.Cu" signal "L3")
		(8 "In3.Cu" signal "L4GND")
		(10 "In4.Cu" signal "L5")
		(12 "In5.Cu" signal "L6GND")
		(14 "In6.Cu" signal "L7VCC")
		(16 "In7.Cu" signal "L8VCC")
		(18 "In8.Cu" signal "L9GND")
		(20 "In9.Cu" signal "L10")
		(22 "In10.Cu" signal "L11GND")
		(24 "In11.Cu" signal "L12")
		(26 "In12.Cu" signal "L13GND")
		(2 "B.Cu" signal "BOTTOM")
		(9 "F.Adhes" user "F.Adhesive")
		(11 "B.Adhes" user "B.Adhesive")
		(13 "F.Paste" user "Package Geometry/Pastemask Top")
		(15 "B.Paste" user "Package Geometry/Pastemask Bottom")
		(5 "F.SilkS" user "Ref Des/Silkscreen Top")
		(7 "B.SilkS" user "Ref Des/Silkscreen Bottom")
		(1 "F.Mask" user "Board Geometry/Soldermask Top")
		(3 "B.Mask" user "Board Geometry/Soldermask Bottom")
		(17 "Dwgs.User" user "User.Drawings")
		(19 "Cmts.User" user "User.Comments")
		(21 "Eco1.User" user "User.Eco1")
		(23 "Eco2.User" user "User.Eco2")
		(25 "Edge.Cuts" user "Board Geometry/Outline")
		(27 "Margin" user)
		(31 "F.CrtYd" user "Package Geometry/Place Bound Top")
		(29 "B.CrtYd" user "Package Geometry/Place Bound Bottom")
		(35 "F.Fab" user "Ref Des/Assembly Top")
		(33 "B.Fab" user "Ref Des/Assembly Bottom")
	)
	(footprint ""
		(layer "F.Cu")
		(at 189.963044 -66.080386 180)
		(property "Reference" "RF2"
			(at -0.8382 -0.67818 180)
			(unlocked yes)
			(layer "F.SilkS")
			(effects
				(font
					(size 0.4064 0.254)
					(thickness 0.1524)
				)
				(justify left)
			)
		)
		(property "Value" ""
			(at 0 0 180)
			(layer "F.Fab")
			(effects
				(font
					(size 1.27 1.27)
				)
			)
		)
		(duplicate_pad_numbers_are_jumpers no)
		(fp_poly
			(pts
				(xy -0.2794 -0.1016) (xy 0.2794 -0.1016) (xy 0.2794 0.9906) (xy -0.2794 0.9906)
			)
			(stroke
				(width 0)
				(type default)
			)
			(fill no)
			(layer "F.CrtYd")
		)
		(fp_line
			(start 0.2794 0.9906)
			(end 0.2794 -0.1016)
			(stroke
				(width 0.1)
				(type default)
			)
			(layer "F.Fab")
		)
		(fp_line
			(start 0.2794 -0.1016)
			(end -0.2794 -0.1016)
			(stroke
				(width 0.1)
				(type default)
			)
			(layer "F.Fab")
		)
		(fp_line
			(start -0.2794 0.9906)
			(end 0.2794 0.9906)
			(stroke
				(width 0.1)
				(type default)
			)
			(layer "F.Fab")
		)
		(fp_line
			(start -0.2794 -0.1016)
			(end -0.2794 0.9906)
			(stroke
				(width 0.1)
				(type default)
			)
			(layer "F.Fab")
		)
		(pad "1" smd rect
			(at 0 0 180)
			(size 0.508 0.508)
			(layers "F.Cu" "F.Mask" "F.Paste")
			(net "VR_PVCCIN_CPU0_AIREF2")
		)
		(pad "2" smd rect
			(at 0 0.889 180)
			(size 0.508 0.508)
			(layers "F.Cu" "F.Mask" "F.Paste")
			(net "ISENSE_PVCCIN_CPU0_PH2_IMON")
		)
		(zone
			(layer "F.Cu")
			(hatch none 0.5)
			(connect_pads
				(clearance 0)
			)
			(min_thickness 0.25)
			(keepout
				(tracks not_allowed)
				(vias allowed)
				(pads allowed)
				(copperpour not_allowed)
				(footprints allowed)
			)
			(placement
				(enabled no)
				(sheetname "")
			)
			(fill
				(thermal_gap 0.5)
				(thermal_bridge_width 0.5)
				(island_removal_mode 0)
			)
			(polygon
				(pts
					(xy 190.217044 -66.715386) (xy 189.709044 -66.715386) (xy 189.709044 -66.334386) (xy 190.217044 -66.334386)
				)
			)
		)
		(zone
			(layer "F.Cu")
			(hatch none 0.5)
			(connect_pads
				(clearance 0)
			)
			(min_thickness 0.25)
			(keepout
				(tracks allowed)
				(vias not_allowed)
				(pads allowed)
				(copperpour not_allowed)
				(footprints allowed)
			)
			(placement
				(enabled no)
				(sheetname "")
			)
			(fill
				(thermal_gap 0.5)
				(thermal_bridge_width 0.5)
				(island_removal_mode 0)
			)
			(polygon
				(pts
					(xy 190.217044 -66.334386) (xy 189.709044 -66.334386) (xy 189.709044 -66.715386) (xy 190.217044 -66.715386)
				)
			)
		)
	)
	(footprint ""
		(layer "F.Cu")
		(at 23.241 -81.6102)
		(property "Reference" "R1D20"
			(at 0 0 0)
			(layer "F.SilkS")
			(hide yes)
			(effects
				(font
					(size 1.27 1.27)
				)
			)
		)
		(property "Value" ""
			(at 0 0 0)
			(layer "F.Fab")
			(effects
				(font
					(size 1.27 1.27)
				)
			)
		)
		(duplicate_pad_numbers_are_jumpers no)
		(fp_poly
			(pts
				(xy -0.2794 -0.1016) (xy 0.2794 -0.1016) (xy 0.2794 0.9906) (xy -0.2794 0.9906)
			)
			(stroke
				(width 0)
				(type default)
			)
			(fill no)
			(layer "F.CrtYd")
		)
		(fp_line
			(start -0.2794 -0.1016)
			(end -0.2794 0.9906)
			(stroke
				(width 0.1)
				(type default)
			)
			(layer "F.Fab")
		)
		(fp_line
			(start -0.2794 0.9906)
			(end 0.2794 0.9906)
			(stroke
				(width 0.1)
				(type default)
			)
			(layer "F.Fab")
		)
		(fp_line
			(start 0.2794 -0.1016)
			(end -0.2794 -0.1016)
			(stroke
				(width 0.1)
				(type default)
			)
			(layer "F.Fab")
		)
		(fp_line
			(start 0.2794 0.9906)
			(end 0.2794 -0.1016)
			(stroke
				(width 0.1)
				(type default)
			)
			(layer "F.Fab")
		)
		(pad "1" smd rect
			(at 0 0)
			(size 0.508 0.508)
			(layers "F.Cu" "F.Mask" "F.Paste")
			(net "A_HSC_CSOUT")
		)
		(pad "2" smd rect
			(at 0 0.889)
			(size 0.508 0.508)
			(layers "F.Cu" "F.Mask" "F.Paste")
			(net "A_HSC_HIGH")
		)
		(zone
			(layer "F.Cu")
			(hatch none 0.5)
			(connect_pads
				(clearance 0)
			)
			(min_thickness 0.25)
			(keepout
				(tracks allowed)
				(vias not_allowed)
				(pads allowed)
				(copperpour not_allowed)
				(footprints allowed)
			)
			(placement
				(enabled no)
				(sheetname "")
			)
			(fill
				(thermal_gap 0.5)
				(thermal_bridge_width 0.5)
				(island_removal_mode 0)
			)
			(polygon
				(pts
					(xy 22.987 -81.3562) (xy 23.495 -81.3562) (xy 23.495 -80.9752) (xy 22.987 -80.9752)
				)
			)
		)
		(zone
			(layer "F.Cu")
			(hatch none 0.5)
			(connect_pads
				(clearance 0)
			)
			(min_thickness 0.25)
			(keepout
				(tracks not_allowed)
				(vias allowed)
				(pads allowed)
				(copperpour not_allowed)
				(footprints allowed)
			)
			(placement
				(enabled no)
				(sheetname "")
			)
			(fill
				(thermal_gap 0.5)
				(thermal_bridge_width 0.5)
				(island_removal_mode 0)
			)
			(polygon
				(pts
					(xy 22.987 -80.9752) (xy 23.495 -80.9752) (xy 23.495 -81.3562) (xy 22.987 -81.3562)
				)
			)
		)
	)
	(footprint ""
		(layer "F.Cu")
		(at 401.066 -47.9425)
		(property "Reference" "R7F32"
			(at 0 0 0)
			(layer "F.SilkS")
			(hide yes)
			(effects
				(font
					(size 1.27 1.27)
				)
			)
		)
		(property "Value" ""
			(at 0 0 0)
			(layer "F.Fab")
			(effects
				(font
					(size 1.27 1.27)
				)
			)
		)
		(duplicate_pad_numbers_are_jumpers no)
		(fp_poly
			(pts
				(xy -0.2794 -0.1016) (xy 0.2794 -0.1016) (xy 0.2794 0.9906) (xy -0.2794 0.9906)
			)
			(stroke
				(width 0)
				(type default)
			)
			(fill no)
			(layer "F.CrtYd")
		)
		(fp_line
			(start -0.2794 -0.1016)
			(end -0.2794 0.9906)
			(stroke
				(width 0.1)
				(type default)
			)
			(layer "F.Fab")
		)
		(fp_line
			(start -0.2794 0.9906)
			(end 0.2794 0.9906)
			(stroke
				(width 0.1)
				(type default)
			)
			(layer "F.Fab")
		)
		(fp_line
			(start 0.2794 -0.1016)
			(end -0.2794 -0.1016)
			(stroke
				(width 0.1)
				(type default)
			)
			(layer "F.Fab")
		)
		(fp_line
			(start 0.2794 0.9906)
			(end 0.2794 -0.1016)
			(stroke
				(width 0.1)
				(type default)
			)
			(layer "F.Fab")
		)
		(pad "1" smd rect
			(at 0 0)
			(size 0.508 0.508)
			(layers "F.Cu" "F.Mask" "F.Paste")
			(net "P3V3_STBY")
		)
		(pad "2" smd rect
			(at 0 0.889)
			(size 0.508 0.508)
			(layers "F.Cu" "F.Mask" "F.Paste")
			(net "PU_BIOS_SPI_HOLD0_N")
		)
		(zone
			(layer "F.Cu")
			(hatch none 0.5)
			(connect_pads
				(clearance 0)
			)
			(min_thickness 0.25)
			(keepout
				(tracks allowed)
				(vias not_allowed)
				(pads allowed)
				(copperpour not_allowed)
				(footprints allowed)
			)
			(placement
				(enabled no)
				(sheetname "")
			)
			(fill
				(thermal_gap 0.5)
				(thermal_bridge_width 0.5)
				(island_removal_mode 0)
			)
			(polygon
				(pts
					(xy 400.812 -47.6885) (xy 401.32 -47.6885) (xy 401.32 -47.3075) (xy 400.812 -47.3075)
				)
			)
		)
		(zone
			(layer "F.Cu")
			(hatch none 0.5)
			(connect_pads
				(clearance 0)
			)
			(min_thickness 0.25)
			(keepout
				(tracks not_allowed)
				(vias allowed)
				(pads allowed)
				(copperpour not_allowed)
				(footprints allowed)
			)
			(placement
				(enabled no)
				(sheetname "")
			)
			(fill
				(thermal_gap 0.5)
				(thermal_bridge_width 0.5)
				(island_removal_mode 0)
			)
			(polygon
				(pts
					(xy 400.812 -47.3075) (xy 401.32 -47.3075) (xy 401.32 -47.6885) (xy 400.812 -47.6885)
				)
			)
		)
	)
)
